# BASEBOARD_FAB2 (Tioga Pass) — schematic netlist excerpt (pin names and nets, part order shuffled) for the footprints in the layout excerpt that follows; sources: Cadence DE-HDL packaged netlist, KiCad conversion of Wiwynn_Tioga_Pass_MB.brd

R1M23  RES  1.00K 1% EMPTY  pkg 0402  page 113 : A = JTAG_MCP_TRST_N ; B = GND
R25W63  RES  100.0K 1% CHIP  pkg 0402  page 146 : A = FM_PE_BMC_WAKE_N ; B = GND
C3L2  CAP  10UF 16V 10% X6S  pkg 0805  page 219 : A = VR_FET_SW_P12V_STBY_PVDDQ_DEF ; B = GND

(kicad_pcb
	(version 20260206)
	(generator "pcbnew")
	(generator_version "10.0")
	(general
		(thickness 1.6)
		(legacy_teardrops no)
	)
	(paper "A4")
	(title_block
		(title "Wiwynn_Tioga_Pass_MB.brd")
		(comment 1 "Tioga Pass / footprints 2929-2931 of 4770")
	)
	(layers
		(0 "F.Cu" signal "TOP")
		(4 "In1.Cu" signal "L2GND")
		(6 "In2.Cu" signal "L3")
		(8 "In3.Cu" signal "L4GND")
		(10 "In4.Cu" signal "L5")
		(12 "In5.Cu" signal "L6GND")
		(14 "In6.Cu" signal "L7VCC")
		(16 "In7.Cu" signal "L8VCC")
		(18 "In8.Cu" signal "L9GND")
		(20 "In9.Cu" signal "L10")
		(22 "In10.Cu" signal "L11GND")
		(24 "In11.Cu" signal "L12")
		(26 "In12.Cu" signal "L13GND")
		(2 "B.Cu" signal "BOTTOM")
		(9 "F.Adhes" user "F.Adhesive")
		(11 "B.Adhes" user "B.Adhesive")
		(13 "F.Paste" user "Package Geometry/Pastemask Top")
		(15 "B.Paste" user "Package Geometry/Pastemask Bottom")
		(5 "F.SilkS" user "Ref Des/Silkscreen Top")
		(7 "B.SilkS" user "Ref Des/Silkscreen Bottom")
		(1 "F.Mask" user "Board Geometry/Soldermask Top")
		(3 "B.Mask" user "Board Geometry/Soldermask Bottom")
		(17 "Dwgs.User" user "User.Drawings")
		(19 "Cmts.User" user "User.Comments")
		(21 "Eco1.User" user "User.Eco1")
		(23 "Eco2.User" user "User.Eco2")
		(25 "Edge.Cuts" user "Board Geometry/Outline")
		(27 "Margin" user)
		(31 "F.CrtYd" user "Package Geometry/Place Bound Top")
		(29 "B.CrtYd" user "Package Geometry/Place Bound Bottom")
		(35 "F.Fab" user "Ref Des/Assembly Top")
		(33 "B.Fab" user "Ref Des/Assembly Bottom")
	)
	(footprint ""
		(layer "B.Cu")
		(at 471.9447 -128.39954 -90)
		(property "Reference" "R1M23"
			(at 0 0 90)
			(layer "B.SilkS")
			(hide yes)
			(effects
				(font
					(size 1.27 1.27)
				)
				(justify mirror)
			)
		)
		(property "Value" ""
			(at 0 0 90)
			(layer "B.Fab")
			(effects
				(font
					(size 1.27 1.27)
				)
				(justify mirror)
			)
		)
		(duplicate_pad_numbers_are_jumpers no)
		(fp_poly
			(pts
				(xy 0.2794 -0.1016) (xy -0.2794 -0.1016) (xy -0.2794 0.9906) (xy 0.2794 0.9906)
			)
			(stroke
				(width 0)
				(type default)
			)
			(fill no)
			(layer "B.CrtYd")
		)
		(fp_line
			(start -0.2794 0.9906)
			(end -0.2794 -0.1016)
			(stroke
				(width 0.1)
				(type default)
			)
			(layer "B.Fab")
		)
		(fp_line
			(start 0.2794 0.9906)
			(end -0.2794 0.9906)
			(stroke
				(width 0.1)
				(type default)
			)
			(layer "B.Fab")
		)
		(fp_line
			(start -0.2794 -0.1016)
			(end 0.2794 -0.1016)
			(stroke
				(width 0.1)
				(type default)
			)
			(layer "B.Fab")
		)
		(fp_line
			(start 0.2794 -0.1016)
			(end 0.2794 0.9906)
			(stroke
				(width 0.1)
				(type default)
			)
			(layer "B.Fab")
		)
		(pad "1" smd rect
			(at 0 0 90)
			(size 0.508 0.508)
			(layers "B.Cu" "B.Mask" "B.Paste")
			(net "JTAG_MCP_TRST_N")
		)
		(pad "2" smd rect
			(at 0 0.889 90)
			(size 0.508 0.508)
			(layers "B.Cu" "B.Mask" "B.Paste")
			(net "GND")
		)
		(zone
			(layer "B.Cu")
			(hatch none 0.5)
			(connect_pads
				(clearance 0)
			)
			(min_thickness 0.25)
			(keepout
				(tracks not_allowed)
				(vias allowed)
				(pads allowed)
				(copperpour not_allowed)
				(footprints allowed)
			)
			(placement
				(enabled no)
				(sheetname "")
			)
			(fill
				(thermal_gap 0.5)
				(thermal_bridge_width 0.5)
				(island_removal_mode 0)
			)
			(polygon
				(pts
					(xy 471.3097 -128.14554) (xy 471.3097 -128.65354) (xy 471.6907 -128.65354) (xy 471.6907 -128.14554)
				)
			)
		)
		(zone
			(layer "B.Cu")
			(hatch none 0.5)
			(connect_pads
				(clearance 0)
			)
			(min_thickness 0.25)
			(keepout
				(tracks allowed)
				(vias not_allowed)
				(pads allowed)
				(copperpour not_allowed)
				(footprints allowed)
			)
			(placement
				(enabled no)
				(sheetname "")
			)
			(fill
				(thermal_gap 0.5)
				(thermal_bridge_width 0.5)
				(island_removal_mode 0)
			)
			(polygon
				(pts
					(xy 471.6907 -128.14554) (xy 471.6907 -128.65354) (xy 471.3097 -128.65354) (xy 471.3097 -128.14554)
				)
			)
		)
	)
	(footprint ""
		(layer "B.Cu")
		(at 417.232846 -44.650152 180)
		(property "Reference" "R25W63"
			(at 0.8382 -0.67818 180)
			(unlocked yes)
			(layer "B.SilkS")
			(effects
				(font
					(size 0.4064 0.254)
					(thickness 0.1524)
				)
				(justify left mirror)
			)
		)
		(property "Value" ""
			(at 0 0 0)
			(layer "B.Fab")
			(effects
				(font
					(size 1.27 1.27)
				)
				(justify mirror)
			)
		)
		(duplicate_pad_numbers_are_jumpers no)
		(fp_poly
			(pts
				(xy 0.2794 -0.1016) (xy -0.2794 -0.1016) (xy -0.2794 0.9906) (xy 0.2794 0.9906)
			)
			(stroke
				(width 0)
				(type default)
			)
			(fill no)
			(layer "B.CrtYd")
		)
		(fp_line
			(start 0.2794 0.9906)
			(end -0.2794 0.9906)
			(stroke
				(width 0.1)
				(type default)
			)
			(layer "B.Fab")
		)
		(fp_line
			(start 0.2794 -0.1016)
			(end 0.2794 0.9906)
			(stroke
				(width 0.1)
				(type default)
			)
			(layer "B.Fab")
		)
		(fp_line
			(start -0.2794 0.9906)
			(end -0.2794 -0.1016)
			(stroke
				(width 0.1)
				(type default)
			)
			(layer "B.Fab")
		)
		(fp_line
			(start -0.2794 -0.1016)
			(end 0.2794 -0.1016)
			(stroke
				(width 0.1)
				(type default)
			)
			(layer "B.Fab")
		)
		(pad "1" smd rect
			(at 0 0)
			(size 0.508 0.508)
			(layers "B.Cu" "B.Mask" "B.Paste")
			(net "FM_PE_BMC_WAKE_N")
		)
		(pad "2" smd rect
			(at 0 0.889)
			(size 0.508 0.508)
			(layers "B.Cu" "B.Mask" "B.Paste")
			(net "GND")
		)
		(zone
			(layer "B.Cu")
			(hatch none 0.5)
			(connect_pads
				(clearance 0)
			)
			(min_thickness 0.25)
			(keepout
				(tracks not_allowed)
				(vias allowed)
				(pads allowed)
				(copperpour not_allowed)
				(footprints allowed)
			)
			(placement
				(enabled no)
				(sheetname "")
			)
			(fill
				(thermal_gap 0.5)
				(thermal_bridge_width 0.5)
				(island_removal_mode 0)
			)
			(polygon
				(pts
					(xy 416.978846 -45.285152) (xy 417.486846 -45.285152) (xy 417.486846 -44.904152) (xy 416.978846 -44.904152)
				)
			)
		)
		(zone
			(layer "B.Cu")
			(hatch none 0.5)
			(connect_pads
				(clearance 0)
			)
			(min_thickness 0.25)
			(keepout
				(tracks allowed)
				(vias not_allowed)
				(pads allowed)
				(copperpour not_allowed)
				(footprints allowed)
			)
			(placement
				(enabled no)
				(sheetname "")
			)
			(fill
				(thermal_gap 0.5)
				(thermal_bridge_width 0.5)
				(island_removal_mode 0)
			)
			(polygon
				(pts
					(xy 416.978846 -44.904152) (xy 417.486846 -44.904152) (xy 417.486846 -45.285152) (xy 416.978846 -45.285152)
				)
			)
		)
	)
	(footprint ""
		(layer "B.Cu")
		(at 348.5896 -153.8732 -90)
		(property "Reference" "C3L2"
			(at 0 0 90)
			(layer "B.SilkS")
			(hide yes)
			(effects
				(font
					(size 1.27 1.27)
				)
				(justify mirror)
			)
		)
		(property "Value" ""
			(at 0 0 90)
			(layer "B.Fab")
			(effects
				(font
					(size 1.27 1.27)
				)
				(justify mirror)
			)
		)
		(duplicate_pad_numbers_are_jumpers no)
		(fp_poly
			(pts
				(xy 0.7239 -0.2159) (xy -0.7239 -0.2159) (xy -0.7239 1.9939) (xy 0.7239 1.9939)
			)
			(stroke
				(width 0)
				(type default)
			)
			(fill no)
			(layer "B.CrtYd")
		)
		(fp_line
			(start -0.7239 1.9939)
			(end -0.7239 -0.2159)
			(stroke
				(width 0.1)
				(type default)
			)
			(layer "B.Fab")
		)
		(fp_line
			(start 0.7239 1.9939)
			(end -0.7239 1.9939)
			(stroke
				(width 0.1)
				(type default)
			)
			(layer "B.Fab")
		)
		(fp_line
			(start -0.7239 -0.2159)
			(end 0.7239 -0.2159)
			(stroke
				(width 0.1)
				(type default)
			)
			(layer "B.Fab")
		)
		(fp_line
			(start 0.7239 -0.2159)
			(end 0.7239 1.9939)
			(stroke
				(width 0.1)
				(type default)
			)
			(layer "B.Fab")
		)
		(pad "1" smd rect
			(at 0 0 90)
			(size 1.27 1.016)
			(layers "B.Cu" "B.Mask" "B.Paste")
			(net "VR_FET_SW_P12V_STBY_PVDDQ_DEF")
		)
		(pad "2" smd rect
			(at 0 1.778 90)
			(size 1.27 1.016)
			(layers "B.Cu" "B.Mask" "B.Paste")
			(net "GND")
		)
		(zone
			(layer "B.Cu")
			(hatch none 0.5)
			(connect_pads
				(clearance 0)
			)
			(min_thickness 0.25)
			(keepout
				(tracks not_allowed)
				(vias allowed)
				(pads allowed)
				(copperpour not_allowed)
				(footprints allowed)
			)
			(placement
				(enabled no)
				(sheetname "")
			)
			(fill
				(thermal_gap 0.5)
				(thermal_bridge_width 0.5)
				(island_removal_mode 0)
			)
			(polygon
				(pts
					(xy 348.0816 -153.2382) (xy 348.0816 -154.5082) (xy 347.3196 -154.5082) (xy 347.3196 -153.2382)
				)
			)
		)
	)
)
